(kicad_pcb
	(version 20260206)
	(generator "pcbnew")
	(generator_version "10.0")
	(general
		(thickness 1.6)
		(legacy_teardrops no)
	)
	(paper "A4")
	(title_block
		(title "01162023_DA0F0TEBIF0_F0T_Expander_BD_F_brd_V02_OCP.brd")
		(comment 1 "Grand Teton / footprints 1367-1373 of 9728")
	)
	(layers
		(0 "F.Cu" signal "TOP")
		(4 "In1.Cu" signal "GND")
		(6 "In2.Cu" signal "VCC")
		(8 "In3.Cu" signal "VCC1")
		(10 "In4.Cu" signal "GND1")
		(12 "In5.Cu" signal "IN1")
		(14 "In6.Cu" signal "GND2")
		(16 "In7.Cu" signal "IN2")
		(18 "In8.Cu" signal "GND3")
		(20 "In9.Cu" signal "IN3")
		(22 "In10.Cu" signal "GND4")
		(24 "In11.Cu" signal "IN4")
		(26 "In12.Cu" signal "GND5")
		(28 "In13.Cu" signal "IN5")
		(30 "In14.Cu" signal "GND6")
		(32 "In15.Cu" signal "IN6")
		(34 "In16.Cu" signal "GND7")
		(2 "B.Cu" signal "BOTTOM")
		(9 "F.Adhes" user "F.Adhesive")
		(11 "B.Adhes" user "B.Adhesive")
		(13 "F.Paste" user "Package Geometry/Pastemask Top")
		(15 "B.Paste" user "Package Geometry/Pastemask Bottom")
		(5 "F.SilkS" user "Ref Des/Silkscreen Top")
		(7 "B.SilkS" user "Ref Des/Silkscreen Bottom")
		(1 "F.Mask" user "Board Geometry/Soldermask Top")
		(3 "B.Mask" user "Board Geometry/Soldermask Bottom")
		(17 "Dwgs.User" user "User.Drawings")
		(19 "Cmts.User" user "User.Comments")
		(21 "Eco1.User" user "User.Eco1")
		(23 "Eco2.User" user "User.Eco2")
		(25 "Edge.Cuts" user "Board Geometry/Outline")
		(27 "Margin" user)
		(31 "F.CrtYd" user "Package Geometry/Place Bound Top")
		(29 "B.CrtYd" user "Package Geometry/Place Bound Bottom")
		(35 "F.Fab" user "Ref Des/Assembly Top")
		(33 "B.Fab" user "Ref Des/Assembly Bottom")
	)
	(footprint ""
		(layer "F.Cu")
		(at 288.072068 -32.848042 90)
		(property "Reference" "PC950"
			(at 0 0 90)
			(layer "F.SilkS")
			(hide yes)
			(effects
				(font
					(size 1.27 1.27)
				)
			)
		)
		(property "Value" ""
			(at 0 0 90)
			(layer "F.Fab")
			(effects
				(font
					(size 1.27 1.27)
				)
			)
		)
		(duplicate_pad_numbers_are_jumpers no)
		(fp_line
			(start 0.7874 -0.4064)
			(end 0.7874 0.4064)
			(stroke
				(width 0.1524)
				(type default)
			)
			(layer "F.SilkS")
		)
		(fp_line
			(start -0.7874 -0.4064)
			(end 0.7874 -0.4064)
			(stroke
				(width 0.1524)
				(type default)
			)
			(layer "F.SilkS")
		)
		(fp_line
			(start 0.7874 0.4064)
			(end -0.7874 0.4064)
			(stroke
				(width 0.1524)
				(type default)
			)
			(layer "F.SilkS")
		)
		(fp_line
			(start -0.7874 0.4064)
			(end -0.7874 -0.4064)
			(stroke
				(width 0.1524)
				(type default)
			)
			(layer "F.SilkS")
		)
		(fp_line
			(start -0.12065 -0.305054)
			(end -0.12065 -0.2794)
			(stroke
				(width 0.1)
				(type default)
			)
			(layer "F.Fab")
		)
		(fp_line
			(start -0.67945 -0.305054)
			(end -0.12065 -0.305054)
			(stroke
				(width 0.1)
				(type default)
			)
			(layer "F.Fab")
		)
		(fp_line
			(start 0.67945 -0.3048)
			(end 0.67945 0.3048)
			(stroke
				(width 0.1)
				(type default)
			)
			(layer "F.Fab")
		)
		(fp_line
			(start 0.12065 -0.3048)
			(end 0.67945 -0.3048)
			(stroke
				(width 0.1)
				(type default)
			)
			(layer "F.Fab")
		)
		(fp_line
			(start 0.12065 -0.2794)
			(end 0.12065 -0.3048)
			(stroke
				(width 0.1)
				(type default)
			)
			(layer "F.Fab")
		)
		(fp_line
			(start -0.12065 -0.2794)
			(end 0.12065 -0.2794)
			(stroke
				(width 0.1)
				(type default)
			)
			(layer "F.Fab")
		)
		(fp_line
			(start 0.120396 0.2794)
			(end -0.12065 0.2794)
			(stroke
				(width 0.1)
				(type default)
			)
			(layer "F.Fab")
		)
		(fp_line
			(start -0.12065 0.2794)
			(end -0.12065 0.3048)
			(stroke
				(width 0.1)
				(type default)
			)
			(layer "F.Fab")
		)
		(fp_line
			(start 0.67945 0.3048)
			(end 0.120396 0.3048)
			(stroke
				(width 0.1)
				(type default)
			)
			(layer "F.Fab")
		)
		(fp_line
			(start 0.120396 0.3048)
			(end 0.120396 0.2794)
			(stroke
				(width 0.1)
				(type default)
			)
			(layer "F.Fab")
		)
		(fp_line
			(start -0.12065 0.3048)
			(end -0.67945 0.3048)
			(stroke
				(width 0.1)
				(type default)
			)
			(layer "F.Fab")
		)
		(fp_line
			(start -0.67945 0.3048)
			(end -0.67945 -0.305054)
			(stroke
				(width 0.1)
				(type default)
			)
			(layer "F.Fab")
		)
		(pad "1" smd circle
			(at -0.40005 0 90)
			(size 0 0)
			(layers "F.Cu" "F.Mask" "F.Paste")
			(net "P3V3_SSD10_CO_GATE")
		)
		(pad "2" smd circle
			(at 0.40005 0 90)
			(size 0 0)
			(layers "F.Cu" "F.Mask" "F.Paste")
			(net "GND")
		)
	)
	(footprint ""
		(layer "F.Cu")
		(at 439.215784 -309.760366 135)
		(property "Reference" "R1454"
			(at 0 0 135)
			(layer "F.SilkS")
			(hide yes)
			(effects
				(font
					(size 1.27 1.27)
				)
			)
		)
		(property "Value" ""
			(at 0 0 135)
			(layer "F.Fab")
			(effects
				(font
					(size 1.27 1.27)
				)
			)
		)
		(duplicate_pad_numbers_are_jumpers no)
		(fp_line
			(start 0.787389 -0.406267)
			(end 0.787389 0.406267)
			(stroke
				(width 0.1524)
				(type default)
			)
			(layer "F.SilkS")
		)
		(fp_line
			(start 0.787389 0.406267)
			(end -0.787389 0.406267)
			(stroke
				(width 0.1524)
				(type default)
			)
			(layer "F.SilkS")
		)
		(fp_line
			(start -0.787389 -0.406267)
			(end 0.787389 -0.406267)
			(stroke
				(width 0.1524)
				(type default)
			)
			(layer "F.SilkS")
		)
		(fp_line
			(start -0.787389 0.406267)
			(end -0.787389 -0.406267)
			(stroke
				(width 0.1524)
				(type default)
			)
			(layer "F.SilkS")
		)
		(fp_line
			(start 0.679446 -0.30479)
			(end 0.679446 0.30479)
			(stroke
				(width 0.1)
				(type default)
			)
			(layer "F.Fab")
		)
		(fp_line
			(start 0.120515 -0.30479)
			(end 0.679446 -0.30479)
			(stroke
				(width 0.1)
				(type default)
			)
			(layer "F.Fab")
		)
		(fp_line
			(start 0.120695 -0.279466)
			(end 0.120515 -0.30479)
			(stroke
				(width 0.1)
				(type default)
			)
			(layer "F.Fab")
		)
		(fp_line
			(start 0.679446 0.30479)
			(end 0.120515 0.30479)
			(stroke
				(width 0.1)
				(type default)
			)
			(layer "F.Fab")
		)
		(fp_line
			(start -0.120695 -0.304969)
			(end -0.120695 -0.279466)
			(stroke
				(width 0.1)
				(type default)
			)
			(layer "F.Fab")
		)
		(fp_line
			(start -0.120695 -0.279466)
			(end 0.120695 -0.279466)
			(stroke
				(width 0.1)
				(type default)
			)
			(layer "F.Fab")
		)
		(fp_line
			(start 0.120335 0.279466)
			(end -0.120695 0.279466)
			(stroke
				(width 0.1)
				(type default)
			)
			(layer "F.Fab")
		)
		(fp_line
			(start 0.120515 0.30479)
			(end 0.120335 0.279466)
			(stroke
				(width 0.1)
				(type default)
			)
			(layer "F.Fab")
		)
		(fp_line
			(start -0.679446 -0.305149)
			(end -0.120695 -0.304969)
			(stroke
				(width 0.1)
				(type default)
			)
			(layer "F.Fab")
		)
		(fp_line
			(start -0.120695 0.279466)
			(end -0.120515 0.30479)
			(stroke
				(width 0.1)
				(type default)
			)
			(layer "F.Fab")
		)
		(fp_line
			(start -0.120515 0.30479)
			(end -0.679446 0.30479)
			(stroke
				(width 0.1)
				(type default)
			)
			(layer "F.Fab")
		)
		(fp_line
			(start -0.679446 0.30479)
			(end -0.679446 -0.305149)
			(stroke
				(width 0.1)
				(type default)
			)
			(layer "F.Fab")
		)
		(pad "1" smd circle
			(at -0.40005 0 135)
			(size 0 0)
			(layers "F.Cu" "F.Mask" "F.Paste")
			(net "GND")
		)
		(pad "2" smd circle
			(at 0.40005 0 135)
			(size 0 0)
			(layers "F.Cu" "F.Mask" "F.Paste")
			(net "PEX3_SPARE0")
		)
	)
	(footprint ""
		(layer "F.Cu")
		(at 432.054254 -48.21809)
		(property "Reference" "PD74"
			(at -3.353054 2.24536 0)
			(unlocked yes)
			(layer "F.SilkS")
			(effects
				(font
					(size 0.7874 0.5842)
					(thickness 0.1524)
				)
				(justify left)
			)
		)
		(property "Value" ""
			(at 0 0 0)
			(layer "F.Fab")
			(effects
				(font
					(size 1.27 1.27)
				)
			)
		)
		(duplicate_pad_numbers_are_jumpers no)
		(fp_line
			(start -3.400044 -1.459992)
			(end 4.107942 -1.459992)
			(stroke
				(width 0.1524)
				(type default)
			)
			(layer "F.SilkS")
		)
		(fp_line
			(start -3.400044 1.459992)
			(end -3.400044 -1.459992)
			(stroke
				(width 0.1524)
				(type default)
			)
			(layer "F.SilkS")
		)
		(fp_line
			(start 4.107942 -1.459992)
			(end 4.107942 1.459992)
			(stroke
				(width 0.1524)
				(type default)
			)
			(layer "F.SilkS")
		)
		(fp_line
			(start 4.107942 1.459992)
			(end -3.400044 1.459992)
			(stroke
				(width 0.1524)
				(type default)
			)
			(layer "F.SilkS")
		)
		(fp_poly
			(pts
				(xy 4.107942 -1.459992) (xy 4.107942 1.459992) (xy 3.308096 1.459992) (xy 3.308096 -1.459992)
			)
			(stroke
				(width 0)
				(type default)
			)
			(fill yes)
			(layer "F.SilkS")
		)
		(fp_line
			(start -2.29997 -1.459992)
			(end 2.29997 -1.459992)
			(stroke
				(width 0.1)
				(type default)
			)
			(layer "F.Fab")
		)
		(fp_line
			(start -2.29997 1.459992)
			(end -2.29997 -1.459992)
			(stroke
				(width 0.1)
				(type default)
			)
			(layer "F.Fab")
		)
		(fp_line
			(start 2.29997 -1.459992)
			(end 2.29997 1.459992)
			(stroke
				(width 0.1)
				(type default)
			)
			(layer "F.Fab")
		)
		(fp_line
			(start 2.29997 1.459992)
			(end -2.29997 1.459992)
			(stroke
				(width 0.1)
				(type default)
			)
			(layer "F.Fab")
		)
		(fp_text user "+"
			(at -4.7752 -0.12065 0)
			(unlocked yes)
			(layer "F.SilkS")
			(effects
				(font
					(size 1.905 1.4224)
					(thickness 0.1524)
				)
				(justify left)
			)
		)
		(fp_text user "-"
			(at 5.4102 0.29845 180)
			(unlocked yes)
			(layer "F.SilkS")
			(effects
				(font
					(size 1.905 1.4224)
					(thickness 0.1524)
				)
				(justify left)
			)
		)
		(fp_text user "+"
			(at -4.7752 -0.12065 0)
			(unlocked yes)
			(layer "F.Fab")
			(effects
				(font
					(size 1.905 1.4224)
					(thickness 0.1524)
				)
				(justify left)
			)
		)
		(fp_text user "-"
			(at 5.4102 0.29845 180)
			(unlocked yes)
			(layer "F.Fab")
			(effects
				(font
					(size 1.905 1.4224)
					(thickness 0.1524)
				)
				(justify left)
			)
		)
		(pad "A" smd rect
			(at -1.999996 0 90)
			(size 1.7018 2.5146)
			(layers "F.Cu" "F.Mask" "F.Paste")
			(net "GND")
		)
		(pad "C" smd rect
			(at 1.999996 0 90)
			(size 1.7018 2.5146)
			(layers "F.Cu" "F.Mask" "F.Paste")
			(net "P3V3_SSD15")
		)
	)
	(footprint ""
		(layer "F.Cu")
		(at 104.267762 -51.019456)
		(property "Reference" "PC398"
			(at 0 0 0)
			(layer "F.SilkS")
			(hide yes)
			(effects
				(font
					(size 1.27 1.27)
				)
			)
		)
		(property "Value" ""
			(at 0 0 0)
			(layer "F.Fab")
			(effects
				(font
					(size 1.27 1.27)
				)
			)
		)
		(duplicate_pad_numbers_are_jumpers no)
		(fp_line
			(start -0.7874 -0.4064)
			(end 0.7874 -0.4064)
			(stroke
				(width 0.1524)
				(type default)
			)
			(layer "F.SilkS")
		)
		(fp_line
			(start -0.7874 0.4064)
			(end -0.7874 -0.4064)
			(stroke
				(width 0.1524)
				(type default)
			)
			(layer "F.SilkS")
		)
		(fp_line
			(start 0.7874 -0.4064)
			(end 0.7874 0.4064)
			(stroke
				(width 0.1524)
				(type default)
			)
			(layer "F.SilkS")
		)
		(fp_line
			(start 0.7874 0.4064)
			(end -0.7874 0.4064)
			(stroke
				(width 0.1524)
				(type default)
			)
			(layer "F.SilkS")
		)
		(fp_line
			(start -0.6858 -0.3048)
			(end -0.1016 -0.3048)
			(stroke
				(width 0.1)
				(type default)
			)
			(layer "F.Fab")
		)
		(fp_line
			(start -0.6858 0.3048)
			(end -0.6858 -0.3048)
			(stroke
				(width 0.1)
				(type default)
			)
			(layer "F.Fab")
		)
		(fp_line
			(start -0.1016 -0.3048)
			(end -0.1016 -0.2794)
			(stroke
				(width 0.1)
				(type default)
			)
			(layer "F.Fab")
		)
		(fp_line
			(start -0.1016 -0.2794)
			(end 0.1016 -0.2794)
			(stroke
				(width 0.1)
				(type default)
			)
			(layer "F.Fab")
		)
		(fp_line
			(start -0.1016 0.2794)
			(end -0.1016 0.3048)
			(stroke
				(width 0.1)
				(type default)
			)
			(layer "F.Fab")
		)
		(fp_line
			(start -0.1016 0.3048)
			(end -0.6858 0.3048)
			(stroke
				(width 0.1)
				(type default)
			)
			(layer "F.Fab")
		)
		(fp_line
			(start 0.1016 -0.3048)
			(end 0.6858 -0.3048)
			(stroke
				(width 0.1)
				(type default)
			)
			(layer "F.Fab")
		)
		(fp_line
			(start 0.1016 -0.2794)
			(end 0.1016 -0.3048)
			(stroke
				(width 0.1)
				(type default)
			)
			(layer "F.Fab")
		)
		(fp_line
			(start 0.1016 0.2794)
			(end -0.1016 0.2794)
			(stroke
				(width 0.1)
				(type default)
			)
			(layer "F.Fab")
		)
		(fp_line
			(start 0.1016 0.3048)
			(end 0.1016 0.2794)
			(stroke
				(width 0.1)
				(type default)
			)
			(layer "F.Fab")
		)
		(fp_line
			(start 0.6858 -0.3048)
			(end 0.6858 0.3048)
			(stroke
				(width 0.1)
				(type default)
			)
			(layer "F.Fab")
		)
		(fp_line
			(start 0.6858 0.3048)
			(end 0.1016 0.3048)
			(stroke
				(width 0.1)
				(type default)
			)
			(layer "F.Fab")
		)
		(pad "1" smd rect
			(at -0.40005 0 180)
			(size 0.4572 0.508)
			(layers "F.Cu" "F.Mask" "F.Paste")
			(net "P12V_SSD3_SS")
		)
		(pad "2" smd rect
			(at 0.40005 0 180)
			(size 0.4572 0.508)
			(layers "F.Cu" "F.Mask" "F.Paste")
			(net "GND")
		)
	)
	(footprint ""
		(layer "F.Cu")
		(at 229.630478 -238.534702 -90)
		(property "Reference" "R6216"
			(at 0 0 270)
			(layer "F.SilkS")
			(hide yes)
			(effects
				(font
					(size 1.27 1.27)
				)
			)
		)
		(property "Value" ""
			(at 0 0 270)
			(layer "F.Fab")
			(effects
				(font
					(size 1.27 1.27)
				)
			)
		)
		(duplicate_pad_numbers_are_jumpers no)
		(fp_line
			(start -0.7874 0.4064)
			(end -0.7874 -0.4064)
			(stroke
				(width 0.1524)
				(type default)
			)
			(layer "F.SilkS")
		)
		(fp_line
			(start 0.7874 0.4064)
			(end -0.7874 0.4064)
			(stroke
				(width 0.1524)
				(type default)
			)
			(layer "F.SilkS")
		)
		(fp_line
			(start -0.7874 -0.4064)
			(end 0.7874 -0.4064)
			(stroke
				(width 0.1524)
				(type default)
			)
			(layer "F.SilkS")
		)
		(fp_line
			(start 0.7874 -0.4064)
			(end 0.7874 0.4064)
			(stroke
				(width 0.1524)
				(type default)
			)
			(layer "F.SilkS")
		)
		(fp_line
			(start -0.67945 0.3048)
			(end -0.67945 -0.305054)
			(stroke
				(width 0.1)
				(type default)
			)
			(layer "F.Fab")
		)
		(fp_line
			(start -0.12065 0.3048)
			(end -0.67945 0.3048)
			(stroke
				(width 0.1)
				(type default)
			)
			(layer "F.Fab")
		)
		(fp_line
			(start 0.120396 0.3048)
			(end 0.120396 0.2794)
			(stroke
				(width 0.1)
				(type default)
			)
			(layer "F.Fab")
		)
		(fp_line
			(start 0.67945 0.3048)
			(end 0.120396 0.3048)
			(stroke
				(width 0.1)
				(type default)
			)
			(layer "F.Fab")
		)
		(fp_line
			(start -0.12065 0.2794)
			(end -0.12065 0.3048)
			(stroke
				(width 0.1)
				(type default)
			)
			(layer "F.Fab")
		)
		(fp_line
			(start 0.120396 0.2794)
			(end -0.12065 0.2794)
			(stroke
				(width 0.1)
				(type default)
			)
			(layer "F.Fab")
		)
		(fp_line
			(start -0.12065 -0.2794)
			(end 0.12065 -0.2794)
			(stroke
				(width 0.1)
				(type default)
			)
			(layer "F.Fab")
		)
		(fp_line
			(start 0.12065 -0.2794)
			(end 0.12065 -0.3048)
			(stroke
				(width 0.1)
				(type default)
			)
			(layer "F.Fab")
		)
		(fp_line
			(start 0.12065 -0.3048)
			(end 0.67945 -0.3048)
			(stroke
				(width 0.1)
				(type default)
			)
			(layer "F.Fab")
		)
		(fp_line
			(start 0.67945 -0.3048)
			(end 0.67945 0.3048)
			(stroke
				(width 0.1)
				(type default)
			)
			(layer "F.Fab")
		)
		(fp_line
			(start -0.67945 -0.305054)
			(end -0.12065 -0.305054)
			(stroke
				(width 0.1)
				(type default)
			)
			(layer "F.Fab")
		)
		(fp_line
			(start -0.12065 -0.305054)
			(end -0.12065 -0.2794)
			(stroke
				(width 0.1)
				(type default)
			)
			(layer "F.Fab")
		)
		(pad "1" smd circle
			(at -0.40005 0 270)
			(size 0 0)
			(layers "F.Cu" "F.Mask" "F.Paste")
			(net "BIC_UART_SW_SEL1")
		)
		(pad "2" smd circle
			(at 0.40005 0 270)
			(size 0 0)
			(layers "F.Cu" "F.Mask" "F.Paste")
			(net "BIC_UART_SW_SEL1_R")
		)
	)
	(footprint ""
		(layer "F.Cu")
		(at 451.79996 -194.360038)
		(property "Reference" "H56"
			(at -4.134612 -5.646166 0)
			(unlocked yes)
			(layer "F.SilkS")
			(effects
				(font
					(size 0.7874 0.5842)
					(thickness 0.1524)
				)
				(justify left)
			)
		)
		(property "Value" ""
			(at 0 0 0)
			(layer "F.Fab")
			(effects
				(font
					(size 1.27 1.27)
				)
			)
		)
		(duplicate_pad_numbers_are_jumpers no)
		(pad "1" thru_hole circle
			(at 0 0)
			(size 10.0076 10.0076)
			(drill 5.6134)
			(layers "*.Cu" "*.Mask")
			(remove_unused_layers no)
			(net "GND")
			(clearance -1.9431)
		)
	)
	(footprint ""
		(layer "F.Cu")
		(at 170.882564 -29.875734)
		(property "Reference" "PU125"
			(at -3.248914 -2.166112 90)
			(unlocked yes)
			(layer "F.SilkS")
			(effects
				(font
					(size 0.7874 0.5842)
					(thickness 0.1524)
				)
			)
		)
		(property "Value" ""
			(at 0 0 0)
			(layer "F.Fab")
			(effects
				(font
					(size 1.27 1.27)
				)
			)
		)
		(duplicate_pad_numbers_are_jumpers no)
		(fp_line
			(start -1.239774 -1.495298)
			(end 1.239774 -1.495298)
			(stroke
				(width 0.1524)
				(type default)
			)
			(layer "F.SilkS")
		)
		(fp_line
			(start -1.239774 1.495298)
			(end -1.239774 -1.495298)
			(stroke
				(width 0.1524)
				(type default)
			)
			(layer "F.SilkS")
		)
		(fp_line
			(start 1.239774 -1.495298)
			(end 1.239774 1.495298)
			(stroke
				(width 0.1524)
				(type default)
			)
			(layer "F.SilkS")
		)
		(fp_line
			(start 1.239774 1.495298)
			(end -1.239774 1.495298)
			(stroke
				(width 0.1524)
				(type default)
			)
			(layer "F.SilkS")
		)
		(fp_poly
			(pts
				(xy -2.173224 -1.829562) (xy -2.89179 -1.11125) (xy -1.814068 -0.75184)
			)
			(stroke
				(width 0)
				(type default)
			)
			(fill yes)
			(layer "F.SilkS")
		)
		(fp_line
			(start -0.8001 -1.050036)
			(end 0.8001 -1.050036)
			(stroke
				(width 0.1)
				(type default)
			)
			(layer "F.Fab")
		)
		(fp_line
			(start -0.8001 1.050036)
			(end -0.8001 -1.050036)
			(stroke
				(width 0.1)
				(type default)
			)
			(layer "F.Fab")
		)
		(fp_line
			(start 0.8001 -1.050036)
			(end 0.8001 1.050036)
			(stroke
				(width 0.1)
				(type default)
			)
			(layer "F.Fab")
		)
		(fp_line
			(start 0.8001 1.050036)
			(end -0.8001 1.050036)
			(stroke
				(width 0.1)
				(type default)
			)
			(layer "F.Fab")
		)
		(fp_poly
			(pts
				(xy -2.458974 -0.508) (xy -2.458974 0.508) (xy -1.442974 0)
			)
			(stroke
				(width 0)
				(type default)
			)
			(fill yes)
			(layer "F.Fab")
		)
		(pad "1_2" smd circle
			(at -0.374904 0 90)
			(size 0 0)
			(layers "F.Cu" "F.Mask" "F.Paste")
			(net "P3V3_AUX")
		)
		(pad "3" smd rect
			(at -0.499872 0.999998)
			(size 0.254 0.7112)
			(layers "F.Cu" "F.Mask" "F.Paste")
			(net "GND")
		)
		(pad "4" smd rect
			(at 0 0.999998)
			(size 0.254 0.7112)
			(layers "F.Cu" "F.Mask" "F.Paste")
			(net "P3V3_SSD6_CO_ILIMIT")
		)
		(pad "5" smd rect
			(at 0.499872 0.999998)
			(size 0.254 0.7112)
			(layers "F.Cu" "F.Mask" "F.Paste")
			(net "P3V3_SSD6_CO_MODE")
		)
		(pad "6_7" smd circle
			(at 0.374904 0 270)
			(size 0 0)
			(layers "F.Cu" "F.Mask" "F.Paste")
			(net "P3V3_SSD6")
		)
		(pad "8" smd rect
			(at 0.499872 -0.999998)
			(size 0.254 0.7112)
			(layers "F.Cu" "F.Mask" "F.Paste")
			(net "P3V3_SSD6_CO_GATE")
		)
		(pad "9" smd rect
			(at 0 -0.999998)
			(size 0.254 0.7112)
			(layers "F.Cu" "F.Mask" "F.Paste")
			(net "P3V3_SSD6_CO_EN")
		)
		(pad "10" smd rect
			(at -0.499872 -0.999998)
			(size 0.254 0.7112)
			(layers "F.Cu" "F.Mask" "F.Paste")
			(net "P3V3_SSD6_CO_DV_DT")
		)
	)
)
